# S9S_MB_2U (Grand Teton) — schematic netlist excerpt (pin names and nets, part order shuffled) for the footprints in the layout excerpt that follows; sources: Cadence DE-HDL packaged netlist, KiCad conversion of 03242023_DA0F0TMBIJ0_F0T_Motherboard_J_brd_V01_OCP.brd

R668  Q_RES  0 5% EMPTY  pkg 0402LF  page 230 : A = I3C_SPD_DDREFGH_CPU1_R_SDA ; B = I3C_SPD_DDREFGH_CPU1_LVC1_R_SDA
PC2166  Q_CAP  0.047UF 25V 10% X7R  pkg C0402  page 163 : A = P12V_OCP_SS_2 ; B = GND

(kicad_pcb
	(version 20260206)
	(generator "pcbnew")
	(generator_version "10.0")
	(general
		(thickness 1.6)
		(legacy_teardrops no)
	)
	(paper "A4")
	(title_block
		(title "03242023_DA0F0TMBIJ0_F0T_Motherboard_J_brd_V01_OCP.brd")
		(comment 1 "Grand Teton / footprints 2351-2352 of 6105")
	)
	(layers
		(0 "F.Cu" signal "TOP")
		(4 "In1.Cu" signal "GND")
		(6 "In2.Cu" signal "IN1")
		(8 "In3.Cu" signal "GND1")
		(10 "In4.Cu" signal "IN2")
		(12 "In5.Cu" signal "GND2")
		(14 "In6.Cu" signal "IN3")
		(16 "In7.Cu" signal "GND3")
		(18 "In8.Cu" signal "VCC")
		(20 "In9.Cu" signal "VCC1")
		(22 "In10.Cu" signal "GND4")
		(24 "In11.Cu" signal "IN4")
		(26 "In12.Cu" signal "GND5")
		(28 "In13.Cu" signal "IN5")
		(30 "In14.Cu" signal "GND6")
		(32 "In15.Cu" signal "IN6")
		(34 "In16.Cu" signal "GND7")
		(2 "B.Cu" signal "BOTTOM")
		(9 "F.Adhes" user "F.Adhesive")
		(11 "B.Adhes" user "B.Adhesive")
		(13 "F.Paste" user "Package Geometry/Pastemask Top")
		(15 "B.Paste" user "Package Geometry/Pastemask Bottom")
		(5 "F.SilkS" user "Ref Des/Silkscreen Top")
		(7 "B.SilkS" user "Ref Des/Silkscreen Bottom")
		(1 "F.Mask" user "Board Geometry/Soldermask Top")
		(3 "B.Mask" user "Board Geometry/Soldermask Bottom")
		(17 "Dwgs.User" user "User.Drawings")
		(19 "Cmts.User" user "User.Comments")
		(21 "Eco1.User" user "User.Eco1")
		(23 "Eco2.User" user "User.Eco2")
		(25 "Edge.Cuts" user "Board Geometry/Outline")
		(27 "Margin" user)
		(31 "F.CrtYd" user "Package Geometry/Place Bound Top")
		(29 "B.CrtYd" user "Package Geometry/Place Bound Bottom")
		(35 "F.Fab" user "Ref Des/Assembly Top")
		(33 "B.Fab" user "Ref Des/Assembly Bottom")
	)
	(footprint ""
		(layer "F.Cu")
		(at 80.32115 -151.383492 180)
		(property "Reference" "R668"
			(at 0 0 180)
			(layer "F.SilkS")
			(hide yes)
			(effects
				(font
					(size 1.27 1.27)
				)
			)
		)
		(property "Value" ""
			(at 0 0 180)
			(layer "F.Fab")
			(effects
				(font
					(size 1.27 1.27)
				)
			)
		)
		(duplicate_pad_numbers_are_jumpers no)
		(fp_line
			(start 0.7874 0.4064)
			(end -0.7874 0.4064)
			(stroke
				(width 0.1524)
				(type default)
			)
			(layer "F.SilkS")
		)
		(fp_line
			(start 0.7874 -0.4064)
			(end 0.7874 0.4064)
			(stroke
				(width 0.1524)
				(type default)
			)
			(layer "F.SilkS")
		)
		(fp_line
			(start -0.7874 0.4064)
			(end -0.7874 -0.4064)
			(stroke
				(width 0.1524)
				(type default)
			)
			(layer "F.SilkS")
		)
		(fp_line
			(start -0.7874 -0.4064)
			(end 0.7874 -0.4064)
			(stroke
				(width 0.1524)
				(type default)
			)
			(layer "F.SilkS")
		)
		(fp_line
			(start 0.67945 0.3048)
			(end 0.120396 0.3048)
			(stroke
				(width 0.1)
				(type default)
			)
			(layer "F.Fab")
		)
		(fp_line
			(start 0.67945 -0.3048)
			(end 0.67945 0.3048)
			(stroke
				(width 0.1)
				(type default)
			)
			(layer "F.Fab")
		)
		(fp_line
			(start 0.12065 -0.2794)
			(end 0.12065 -0.3048)
			(stroke
				(width 0.1)
				(type default)
			)
			(layer "F.Fab")
		)
		(fp_line
			(start 0.12065 -0.3048)
			(end 0.67945 -0.3048)
			(stroke
				(width 0.1)
				(type default)
			)
			(layer "F.Fab")
		)
		(fp_line
			(start 0.120396 0.3048)
			(end 0.120396 0.2794)
			(stroke
				(width 0.1)
				(type default)
			)
			(layer "F.Fab")
		)
		(fp_line
			(start 0.120396 0.2794)
			(end -0.12065 0.2794)
			(stroke
				(width 0.1)
				(type default)
			)
			(layer "F.Fab")
		)
		(fp_line
			(start -0.12065 0.3048)
			(end -0.67945 0.3048)
			(stroke
				(width 0.1)
				(type default)
			)
			(layer "F.Fab")
		)
		(fp_line
			(start -0.12065 0.2794)
			(end -0.12065 0.3048)
			(stroke
				(width 0.1)
				(type default)
			)
			(layer "F.Fab")
		)
		(fp_line
			(start -0.12065 -0.2794)
			(end 0.12065 -0.2794)
			(stroke
				(width 0.1)
				(type default)
			)
			(layer "F.Fab")
		)
		(fp_line
			(start -0.12065 -0.305054)
			(end -0.12065 -0.2794)
			(stroke
				(width 0.1)
				(type default)
			)
			(layer "F.Fab")
		)
		(fp_line
			(start -0.67945 0.3048)
			(end -0.67945 -0.305054)
			(stroke
				(width 0.1)
				(type default)
			)
			(layer "F.Fab")
		)
		(fp_line
			(start -0.67945 -0.305054)
			(end -0.12065 -0.305054)
			(stroke
				(width 0.1)
				(type default)
			)
			(layer "F.Fab")
		)
		(pad "1" smd circle
			(at -0.40005 0 180)
			(size 0 0)
			(layers "F.Cu" "F.Mask" "F.Paste")
			(net "I3C_SPD_DDREFGH_CPU1_R_SDA")
		)
		(pad "2" smd circle
			(at 0.40005 0 180)
			(size 0 0)
			(layers "F.Cu" "F.Mask" "F.Paste")
			(net "I3C_SPD_DDREFGH_CPU1_LVC1_R_SDA")
		)
	)
	(footprint ""
		(layer "F.Cu")
		(at 66.369438 -31.887922 90)
		(property "Reference" "PC2166"
			(at 0 0 90)
			(layer "F.SilkS")
			(hide yes)
			(effects
				(font
					(size 1.27 1.27)
				)
			)
		)
		(property "Value" ""
			(at 0 0 90)
			(layer "F.Fab")
			(effects
				(font
					(size 1.27 1.27)
				)
			)
		)
		(duplicate_pad_numbers_are_jumpers no)
		(fp_line
			(start 0.7874 -0.4064)
			(end 0.7874 0.4064)
			(stroke
				(width 0.1524)
				(type default)
			)
			(layer "F.SilkS")
		)
		(fp_line
			(start -0.7874 -0.4064)
			(end 0.7874 -0.4064)
			(stroke
				(width 0.1524)
				(type default)
			)
			(layer "F.SilkS")
		)
		(fp_line
			(start 0.7874 0.4064)
			(end -0.7874 0.4064)
			(stroke
				(width 0.1524)
				(type default)
			)
			(layer "F.SilkS")
		)
		(fp_line
			(start -0.7874 0.4064)
			(end -0.7874 -0.4064)
			(stroke
				(width 0.1524)
				(type default)
			)
			(layer "F.SilkS")
		)
		(fp_line
			(start -0.12065 -0.305054)
			(end -0.12065 -0.2794)
			(stroke
				(width 0.1)
				(type default)
			)
			(layer "F.Fab")
		)
		(fp_line
			(start -0.67945 -0.305054)
			(end -0.12065 -0.305054)
			(stroke
				(width 0.1)
				(type default)
			)
			(layer "F.Fab")
		)
		(fp_line
			(start 0.67945 -0.3048)
			(end 0.67945 0.3048)
			(stroke
				(width 0.1)
				(type default)
			)
			(layer "F.Fab")
		)
		(fp_line
			(start 0.12065 -0.3048)
			(end 0.67945 -0.3048)
			(stroke
				(width 0.1)
				(type default)
			)
			(layer "F.Fab")
		)
		(fp_line
			(start 0.12065 -0.2794)
			(end 0.12065 -0.3048)
			(stroke
				(width 0.1)
				(type default)
			)
			(layer "F.Fab")
		)
		(fp_line
			(start -0.12065 -0.2794)
			(end 0.12065 -0.2794)
			(stroke
				(width 0.1)
				(type default)
			)
			(layer "F.Fab")
		)
		(fp_line
			(start 0.120396 0.2794)
			(end -0.12065 0.2794)
			(stroke
				(width 0.1)
				(type default)
			)
			(layer "F.Fab")
		)
		(fp_line
			(start -0.12065 0.2794)
			(end -0.12065 0.3048)
			(stroke
				(width 0.1)
				(type default)
			)
			(layer "F.Fab")
		)
		(fp_line
			(start 0.67945 0.3048)
			(end 0.120396 0.3048)
			(stroke
				(width 0.1)
				(type default)
			)
			(layer "F.Fab")
		)
		(fp_line
			(start 0.120396 0.3048)
			(end 0.120396 0.2794)
			(stroke
				(width 0.1)
				(type default)
			)
			(layer "F.Fab")
		)
		(fp_line
			(start -0.12065 0.3048)
			(end -0.67945 0.3048)
			(stroke
				(width 0.1)
				(type default)
			)
			(layer "F.Fab")
		)
		(fp_line
			(start -0.67945 0.3048)
			(end -0.67945 -0.305054)
			(stroke
				(width 0.1)
				(type default)
			)
			(layer "F.Fab")
		)
		(pad "1" smd circle
			(at -0.40005 0 90)
			(size 0 0)
			(layers "F.Cu" "F.Mask" "F.Paste")
			(net "P12V_OCP_SS_2")
		)
		(pad "2" smd circle
			(at 0.40005 0 90)
			(size 0 0)
			(layers "F.Cu" "F.Mask" "F.Paste")
			(net "GND")
		)
	)
)
